(kicad_pcb
	(version 20241229)
	(generator "pcbnew")
	(generator_version "9.0")
	(general
		(thickness 1.63)
		(legacy_teardrops no)
	)
	(paper "A4")
	(title_block
		(title "CM4 Baseboard")
		(date "2026-01-05")
		(rev "1.1.1")
		(company "Antmicro Ltd")
		(comment 1 "www.antmicro.com")
		(comment 9 "footprints 74-78 of 506")
	)
	(layers
		(0 "F.Cu" signal)
		(4 "In1.Cu" power)
		(6 "In2.Cu" power)
		(8 "In3.Cu" signal)
		(10 "In4.Cu" signal)
		(2 "B.Cu" signal)
		(9 "F.Adhes" user "F.Adhesive")
		(11 "B.Adhes" user "B.Adhesive")
		(13 "F.Paste" user)
		(15 "B.Paste" user)
		(5 "F.SilkS" user "F.Silkscreen")
		(7 "B.SilkS" user "B.Silkscreen")
		(1 "F.Mask" user)
		(3 "B.Mask" user)
		(17 "Dwgs.User" user "User.Drawings")
		(19 "Cmts.User" user "User.Comments")
		(21 "Eco1.User" user "User.Eco1")
		(23 "Eco2.User" user "User.Eco2")
		(25 "Edge.Cuts" user)
		(27 "Margin" user)
		(31 "F.CrtYd" user "F.Courtyard")
		(29 "B.CrtYd" user "B.Courtyard")
		(35 "F.Fab" user)
		(33 "B.Fab" user)
	)
	(footprint "antmicro-footprints:TP_SMD_0.75mm"
		(layer "F.Cu")
		(at 117.717962 141.5165 -90)
		(property "Reference" "TP303"
			(at 0.58 -0.4 90)
			(layer "F.SilkS")
			(effects
				(font
					(size 0.7 0.7)
					(thickness 0.15)
				)
				(justify right bottom)
			)
		)
		(property "Value" "TP_0.75mm_SMD"
			(at 0 1.2 90)
			(layer "F.Fab")
			(effects
				(font
					(size 0.7 0.7)
					(thickness 0.15)
				)
				(justify right bottom)
			)
		)
		(property "Author" "Antmicro"
			(at 0 0 270)
			(unlocked yes)
			(layer "F.Fab")
			(hide yes)
			(effects
				(font
					(size 1 1)
					(thickness 0.15)
				)
			)
		)
		(property "License" "Apache-2.0"
			(at 0 0 270)
			(unlocked yes)
			(layer "F.Fab")
			(hide yes)
			(effects
				(font
					(size 1 1)
					(thickness 0.15)
				)
			)
		)
		(property "MPN" ""
			(at 0 0 270)
			(unlocked yes)
			(layer "F.Fab")
			(hide yes)
			(effects
				(font
					(size 1 1)
					(thickness 0.15)
				)
			)
		)
		(property "Manufacturer" ""
			(at 0 0 270)
			(unlocked yes)
			(layer "F.Fab")
			(hide yes)
			(effects
				(font
					(size 1 1)
					(thickness 0.15)
				)
			)
		)
		(sheetname "/Supply/")
		(sheetfile "supply.kicad_sch")
		(attr exclude_from_pos_files exclude_from_bom)
		(fp_circle
			(center 0 0)
			(end 0.475 0)
			(stroke
				(width 0.05)
				(type default)
			)
			(fill no)
			(layer "F.CrtYd")
		)
		(fp_text user "${REFERENCE}"
			(at -0.4 2.7 270)
			(layer "F.Fab")
			(effects
				(font
					(size 0.7 0.7)
					(thickness 0.15)
				)
				(justify left bottom)
			)
		)
		(fp_text user "Author: Antmicro"
			(at -0.4 3.901 270)
			(layer "F.Fab")
			(effects
				(font
					(size 0.7 0.7)
					(thickness 0.15)
				)
				(justify left bottom)
			)
		)
		(fp_text user "License: Apache-2.0"
			(at -0.4 5.101 270)
			(layer "F.Fab")
			(effects
				(font
					(size 0.7 0.7)
					(thickness 0.15)
				)
				(justify left bottom)
			)
		)
		(pad "1" smd circle
			(at 0 0 270)
			(size 0.75 0.75)
			(layers "F.Cu" "F.Mask")
			(net 380 "/Compute module/NVMe_EN")
			(pinfunction "1")
			(pintype "passive")
		)
	)
	(footprint "antmicro-footprints:C_0402_1005Metric"
		(layer "F.Cu")
		(at 66.092962 177.7005 -90)
		(descr "Capacitor SMD 0402")
		(tags "capacitor SMD 0402")
		(property "Reference" "C816"
			(at -2.704 13.955 90)
			(layer "F.SilkS")
			(effects
				(font
					(size 0.7 0.7)
					(thickness 0.15)
				)
				(justify right bottom)
			)
		)
		(property "Value" "C_template_name_0402"
			(at -1.022927 2.155213 90)
			(layer "F.Fab")
			(effects
				(font
					(size 0.7 0.7)
					(thickness 0.15)
				)
				(justify right bottom)
			)
		)
		(property "Datasheet" "template_datasheet"
			(at 0 0 270)
			(layer "F.Fab")
			(hide yes)
			(effects
				(font
					(size 1.27 1.27)
					(thickness 0.15)
				)
			)
		)
		(property "MPN" "template_MPN"
			(at 0 0 270)
			(unlocked yes)
			(layer "F.Fab")
			(hide yes)
			(effects
				(font
					(size 1 1)
					(thickness 0.15)
				)
			)
		)
		(property "Manufacturer" "template_manufacturer"
			(at 0 0 270)
			(unlocked yes)
			(layer "F.Fab")
			(hide yes)
			(effects
				(font
					(size 1 1)
					(thickness 0.15)
				)
			)
		)
		(property "License" "Apache-2.0"
			(at 0 0 270)
			(unlocked yes)
			(layer "F.Fab")
			(hide yes)
			(effects
				(font
					(size 1 1)
					(thickness 0.15)
				)
			)
		)
		(property "Author" "Antmicro"
			(at 0 0 270)
			(unlocked yes)
			(layer "F.Fab")
			(hide yes)
			(effects
				(font
					(size 1 1)
					(thickness 0.15)
				)
			)
		)
		(property "Val" "template_value"
			(at 0 0 270)
			(unlocked yes)
			(layer "F.Fab")
			(hide yes)
			(effects
				(font
					(size 1 1)
					(thickness 0.15)
				)
			)
		)
		(property "Voltage" "template_voltage"
			(at 0 0 270)
			(unlocked yes)
			(layer "F.Fab")
			(hide yes)
			(effects
				(font
					(size 1 1)
					(thickness 0.15)
				)
			)
		)
		(property "Dielectric" "template_dielectric"
			(at 0 0 270)
			(unlocked yes)
			(layer "F.Fab")
			(hide yes)
			(effects
				(font
					(size 1 1)
					(thickness 0.15)
				)
			)
		)
		(sheetname "/Peripherals/")
		(sheetfile "peripherals.kicad_sch")
		(attr smd exclude_from_pos_files exclude_from_bom dnp)
		(fp_rect
			(start -0.925 -0.47)
			(end 0.925 0.47)
			(stroke
				(width 0.05)
				(type default)
			)
			(fill no)
			(layer "F.CrtYd")
		)
		(fp_line
			(start -0.494 0.248)
			(end -0.494 -0.25)
			(stroke
				(width 0.15)
				(type solid)
			)
			(layer "F.Fab")
		)
		(fp_line
			(start 0.504 0.248)
			(end -0.494 0.248)
			(stroke
				(width 0.15)
				(type solid)
			)
			(layer "F.Fab")
		)
		(fp_line
			(start -0.494 -0.25)
			(end 0.504 -0.25)
			(stroke
				(width 0.15)
				(type solid)
			)
			(layer "F.Fab")
		)
		(fp_line
			(start 0.504 -0.25)
			(end 0.504 0.248)
			(stroke
				(width 0.15)
				(type solid)
			)
			(layer "F.Fab")
		)
		(fp_text user "${REFERENCE}"
			(at -0.939 4.599 270)
			(layer "F.Fab")
			(effects
				(font
					(size 0.7 0.7)
					(thickness 0.15)
				)
				(justify left bottom)
			)
		)
		(fp_text user "License: Apache-2.0"
			(at -0.939 5.799 270)
			(layer "F.Fab")
			(effects
				(font
					(size 0.7 0.7)
					(thickness 0.15)
				)
				(justify left bottom)
			)
		)
		(fp_text user "Author: Antmicro"
			(at -0.939 3.399 270)
			(layer "F.Fab")
			(effects
				(font
					(size 0.7 0.7)
					(thickness 0.15)
				)
				(justify left bottom)
			)
		)
		(pad "1" smd roundrect
			(at -0.48 0 270)
			(size 0.59 0.64)
			(layers "F.Cu" "F.Mask" "F.Paste")
			(roundrect_rratio 0.25)
			(net 3 "GND")
			(pintype "passive")
		)
		(pad "2" smd roundrect
			(at 0.48 0 270)
			(size 0.59 0.64)
			(layers "F.Cu" "F.Mask" "F.Paste")
			(roundrect_rratio 0.25)
			(net 109 "Net-(C816-Pad2)")
			(pintype "passive")
		)
	)
	(footprint "antmicro-footprints:Conn_JST_SH_1x4_SM04B-SRSS-TB-LF-SN"
		(layer "F.Cu")
		(at 122.817962 114.6165 180)
		(property "Reference" "J802"
			(at 3.81 2.53 90)
			(layer "F.SilkS")
			(effects
				(font
					(size 0.7 0.7)
					(thickness 0.15)
				)
				(justify right bottom)
			)
		)
		(property "Value" "JST_SH_1x4_SM04B-SRSS-TB-LF-SN"
			(at 0 3.9 0)
			(layer "F.Fab")
			(effects
				(font
					(size 0.7 0.7)
					(thickness 0.15)
				)
				(justify right bottom)
			)
		)
		(property "Datasheet" "https://www.jst-mfg.com/product/pdf/eng/eSH.pdf"
			(at 0 0 180)
			(layer "F.Fab")
			(hide yes)
			(effects
				(font
					(size 1.27 1.27)
					(thickness 0.15)
				)
			)
		)
		(property "MPN" "SM04B-SRSS-TB(LF)(SN)"
			(at 0 0 180)
			(unlocked yes)
			(layer "F.Fab")
			(hide yes)
			(effects
				(font
					(size 1 1)
					(thickness 0.15)
				)
			)
		)
		(property "Manufacturer" "JST Automotive Connectors"
			(at 0 0 180)
			(unlocked yes)
			(layer "F.Fab")
			(hide yes)
			(effects
				(font
					(size 1 1)
					(thickness 0.15)
				)
			)
		)
		(property "Author" "Antmicro"
			(at 0 0 180)
			(unlocked yes)
			(layer "F.Fab")
			(hide yes)
			(effects
				(font
					(size 1 1)
					(thickness 0.15)
				)
			)
		)
		(property "License" "Apache-2.0"
			(at 0 0 180)
			(unlocked yes)
			(layer "F.Fab")
			(hide yes)
			(effects
				(font
					(size 1 1)
					(thickness 0.15)
				)
			)
		)
		(sheetname "/Peripherals/")
		(sheetfile "peripherals.kicad_sch")
		(attr smd)
		(fp_line
			(start 3.2 -2)
			(end 3.2 0.6)
			(stroke
				(width 0.15)
				(type solid)
			)
			(layer "F.SilkS")
		)
		(fp_line
			(start 2 -2)
			(end 3.2 -2)
			(stroke
				(width 0.15)
				(type solid)
			)
			(layer "F.SilkS")
		)
		(fp_line
			(start -2 2.6)
			(end 2 2.6)
			(stroke
				(width 0.15)
				(type solid)
			)
			(layer "F.SilkS")
		)
		(fp_line
			(start -2 -2)
			(end -3.2 -2)
			(stroke
				(width 0.15)
				(type solid)
			)
			(layer "F.SilkS")
		)
		(fp_line
			(start -3.2 -2)
			(end -3.2 0.6)
			(stroke
				(width 0.15)
				(type solid)
			)
			(layer "F.SilkS")
		)
		(fp_circle
			(center -2.1 -2.5)
			(end -2.05 -2.5)
			(stroke
				(width 0.15)
				(type solid)
			)
			(fill yes)
			(layer "F.SilkS")
		)
		(fp_rect
			(start -3.65 -3.14)
			(end 3.65 2.9)
			(stroke
				(width 0.05)
				(type solid)
			)
			(fill no)
			(layer "F.CrtYd")
		)
		(fp_rect
			(start -3 -2.475)
			(end 3 2.475)
			(stroke
				(width 0.15)
				(type solid)
			)
			(fill no)
			(layer "F.Fab")
		)
		(fp_text user "${REFERENCE}"
			(at -4 8.28 180)
			(layer "F.Fab")
			(effects
				(font
					(size 0.7 0.7)
					(thickness 0.15)
				)
				(justify left bottom)
			)
		)
		(fp_text user "Author: Antmicro"
			(at -4 7.08 180)
			(layer "F.Fab")
			(effects
				(font
					(size 0.7 0.7)
					(thickness 0.15)
				)
				(justify left bottom)
			)
		)
		(fp_text user "License: Apache-2.0"
			(at -4 5.88 180)
			(layer "F.Fab")
			(effects
				(font
					(size 0.7 0.7)
					(thickness 0.15)
				)
				(justify left bottom)
			)
		)
		(pad "1" smd roundrect
			(at -1.5 -2.12)
			(size 0.6 1.55)
			(layers "F.Cu" "F.Mask" "F.Paste")
			(roundrect_rratio 0.25)
			(net 3 "GND")
			(pintype "passive")
		)
		(pad "2" smd roundrect
			(at -0.5 -2.12)
			(size 0.6 1.55)
			(layers "F.Cu" "F.Mask" "F.Paste")
			(roundrect_rratio 0.25)
			(net 9 "+3V3")
			(pintype "passive")
		)
		(pad "3" smd roundrect
			(at 0.5 -2.12)
			(size 0.6 1.55)
			(layers "F.Cu" "F.Mask" "F.Paste")
			(roundrect_rratio 0.25)
			(net 143 "/CSI/I_{2}C1.SDA")
			(pintype "passive")
		)
		(pad "4" smd roundrect
			(at 1.5 -2.12)
			(size 0.6 1.55)
			(layers "F.Cu" "F.Mask" "F.Paste")
			(roundrect_rratio 0.25)
			(net 142 "/CSI/I_{2}C1.SCL")
			(pintype "passive")
		)
		(pad "MP" smd roundrect
			(at -2.8 1.755 180)
			(size 1.2 1.8)
			(layers "F.Cu" "F.Mask" "F.Paste")
			(roundrect_rratio 0.25)
			(net 3 "GND")
			(pintype "passive")
		)
		(pad "MP" smd roundrect
			(at 2.8 1.755 180)
			(size 1.2 1.8)
			(layers "F.Cu" "F.Mask" "F.Paste")
			(roundrect_rratio 0.25)
			(net 3 "GND")
			(pintype "passive")
		)
	)
	(footprint "antmicro-footprints:LED_0603_1608Metric_G"
		(layer "F.Cu")
		(at 75.627962 133.3165 180)
		(descr "LED SMD 0603 Green")
		(tags "LED SMD 0603 Green")
		(property "Reference" "D912"
			(at 5.177962 -2.105775 0)
			(layer "F.SilkS")
			(effects
				(font
					(size 0.7 0.7)
					(thickness 0.15)
				)
				(justify right bottom)
			)
		)
		(property "Value" "LED_G_0603_KP-1608CGCK"
			(at -0.001 1.599 0)
			(layer "F.Fab")
			(effects
				(font
					(size 0.7 0.7)
					(thickness 0.15)
				)
				(justify right bottom)
			)
		)
		(property "Datasheet" "http://www.kingbright.com/attachments/file/psearch//000/00/00/KP-1608CGCK(Ver.23B).pdf"
			(at 0 0 180)
			(layer "F.Fab")
			(hide yes)
			(effects
				(font
					(size 1.27 1.27)
					(thickness 0.15)
				)
			)
		)
		(property "MPN" "KP-1608CGCK"
			(at 0 0 180)
			(unlocked yes)
			(layer "F.Fab")
			(hide yes)
			(effects
				(font
					(size 1 1)
					(thickness 0.15)
				)
			)
		)
		(property "Manufacturer" "Kingbright"
			(at 0 0 180)
			(unlocked yes)
			(layer "F.Fab")
			(hide yes)
			(effects
				(font
					(size 1 1)
					(thickness 0.15)
				)
			)
		)
		(property "Color" "Green"
			(at 0 0 180)
			(unlocked yes)
			(layer "F.Fab")
			(hide yes)
			(effects
				(font
					(size 1 1)
					(thickness 0.15)
				)
			)
		)
		(property "Author" "Antmicro"
			(at 0 0 180)
			(unlocked yes)
			(layer "F.Fab")
			(hide yes)
			(effects
				(font
					(size 1 1)
					(thickness 0.15)
				)
			)
		)
		(property "License" "Apache-2.0"
			(at 0 0 180)
			(unlocked yes)
			(layer "F.Fab")
			(hide yes)
			(effects
				(font
					(size 1 1)
					(thickness 0.15)
				)
			)
		)
		(sheetname "/USB/")
		(sheetfile "usb.kicad_sch")
		(attr smd)
		(fp_line
			(start 0.22 0.35)
			(end -0.22 0.35)
			(stroke
				(width 0.15)
				(type solid)
			)
			(layer "F.SilkS")
		)
		(fp_line
			(start 0.22 -0.35)
			(end -0.22 -0.35)
			(stroke
				(width 0.15)
				(type solid)
			)
			(layer "F.SilkS")
		)
		(fp_line
			(start 0.105328 0.201008)
			(end 0.105328 -0.198992)
			(stroke
				(width 0.1)
				(type solid)
			)
			(layer "F.SilkS")
		)
		(fp_line
			(start 0.105328 0.201008)
			(end -0.094672 0.001008)
			(stroke
				(width 0.1)
				(type solid)
			)
			(layer "F.SilkS")
		)
		(fp_line
			(start 0.105328 0.001008)
			(end 0.24 0.001)
			(stroke
				(width 0.1)
				(type solid)
			)
			(layer "F.SilkS")
		)
		(fp_line
			(start -0.094672 0.201008)
			(end -0.094672 -0.198992)
			(stroke
				(width 0.1)
				(type solid)
			)
			(layer "F.SilkS")
		)
		(fp_line
			(start -0.094672 0.001008)
			(end 0.105328 -0.198992)
			(stroke
				(width 0.1)
				(type solid)
			)
			(layer "F.SilkS")
		)
		(fp_line
			(start -0.094672 0.001008)
			(end -0.24 0.001008)
			(stroke
				(width 0.1)
				(type solid)
			)
			(layer "F.SilkS")
		)
		(fp_line
			(start -1.18 -0.319)
			(end -1.18 0.321)
			(stroke
				(width 0.15)
				(type solid)
			)
			(layer "F.SilkS")
		)
		(fp_rect
			(start 1.25 0.65)
			(end -1.25 -0.65)
			(stroke
				(width 0.05)
				(type solid)
			)
			(fill no)
			(layer "F.CrtYd")
		)
		(fp_line
			(start 0.599 0)
			(end 0.201 0)
			(stroke
				(width 0.15)
				(type solid)
			)
			(layer "F.Fab")
		)
		(fp_line
			(start 0.201 0.2)
			(end 0.201 0)
			(stroke
				(width 0.15)
				(type solid)
			)
			(layer "F.Fab")
		)
		(fp_line
			(start 0.201 0)
			(end 0.201 -0.202)
			(stroke
				(width 0.15)
				(type solid)
			)
			(layer "F.Fab")
		)
		(fp_line
			(start 0.201 -0.202)
			(end -0.101 0)
			(stroke
				(width 0.15)
				(type solid)
			)
			(layer "F.Fab")
		)
		(fp_line
			(start -0.101 0)
			(end 0.201 0.2)
			(stroke
				(width 0.15)
				(type solid)
			)
			(layer "F.Fab")
		)
		(fp_line
			(start -0.199 0.2)
			(end -0.199 0.1)
			(stroke
				(width 0.15)
				(type solid)
			)
			(layer "F.Fab")
		)
		(fp_line
			(start -0.199 0)
			(end -0.597 0)
			(stroke
				(width 0.15)
				(type solid)
			)
			(layer "F.Fab")
		)
		(fp_line
			(start -0.199 -0.202)
			(end -0.199 0.1)
			(stroke
				(width 0.15)
				(type solid)
			)
			(layer "F.Fab")
		)
		(fp_rect
			(start 0.848 0.4)
			(end -0.85 -0.402)
			(stroke
				(width 0.15)
				(type solid)
			)
			(fill no)
			(layer "F.Fab")
		)
		(fp_text user "${REFERENCE}"
			(at -1.4224 5.999 180)
			(layer "F.Fab")
			(effects
				(font
					(size 0.7 0.7)
					(thickness 0.15)
				)
				(justify left bottom)
			)
		)
		(fp_text user "Author: Antmicro"
			(at -1.4224 4.799 180)
			(layer "F.Fab")
			(effects
				(font
					(size 0.7 0.7)
					(thickness 0.15)
				)
				(justify left bottom)
			)
		)
		(fp_text user "License: Apache-2.0"
			(at -1.4224 3.599 180)
			(layer "F.Fab")
			(effects
				(font
					(size 0.7 0.7)
					(thickness 0.15)
				)
				(justify left bottom)
			)
		)
		(pad "1" smd roundrect
			(at -0.7 0)
			(size 0.8 1)
			(layers "F.Cu" "F.Mask" "F.Paste")
			(roundrect_rratio 0.2)
			(net 488 "Net-(D912-C)")
			(pinfunction "C")
			(pintype "passive")
		)
		(pad "2" smd roundrect
			(at 0.7 0)
			(size 0.8 1)
			(layers "F.Cu" "F.Mask" "F.Paste")
			(roundrect_rratio 0.2)
			(net 489 "Net-(D912-A)")
			(pinfunction "A")
			(pintype "passive")
		)
	)
	(footprint "antmicro-footprints:R_0402_1005Metric"
		(layer "F.Cu")
		(at 123.805476 164.8165)
		(descr "Resistor SMD 0402")
		(tags "resistor SMD 0402")
		(property "Reference" "R507"
			(at -3.837514 0.46 0)
			(layer "F.SilkS")
			(effects
				(font
					(size 0.7 0.7)
					(thickness 0.15)
				)
				(justify left bottom)
			)
		)
		(property "Value" "R_10k_0402"
			(at -1.011843 1.772047 0)
			(layer "F.Fab")
			(effects
				(font
					(size 0.7 0.7)
					(thickness 0.15)
				)
				(justify left bottom)
			)
		)
		(property "Datasheet" "https://www.bourns.com/docs/product-datasheets/cr.pdf"
			(at 0 0 0)
			(layer "F.Fab")
			(hide yes)
			(effects
				(font
					(size 1.27 1.27)
					(thickness 0.15)
				)
			)
		)
		(property "Manufacturer" "Bourns"
			(at 0 0 0)
			(unlocked yes)
			(layer "F.Fab")
			(hide yes)
			(effects
				(font
					(size 1 1)
					(thickness 0.15)
				)
			)
		)
		(property "MPN" "CR0402-FX-1002GLF"
			(at 0 0 0)
			(unlocked yes)
			(layer "F.Fab")
			(hide yes)
			(effects
				(font
					(size 1 1)
					(thickness 0.15)
				)
			)
		)
		(property "Val" "10k"
			(at 0 0 0)
			(unlocked yes)
			(layer "F.Fab")
			(hide yes)
			(effects
				(font
					(size 1 1)
					(thickness 0.15)
				)
			)
		)
		(property "License" "Apache-2.0"
			(at 0 0 0)
			(unlocked yes)
			(layer "F.Fab")
			(hide yes)
			(effects
				(font
					(size 1 1)
					(thickness 0.15)
				)
			)
		)
		(property "Author" "Antmicro"
			(at 0 0 0)
			(unlocked yes)
			(layer "F.Fab")
			(hide yes)
			(effects
				(font
					(size 1 1)
					(thickness 0.15)
				)
			)
		)
		(property "Tolerance" "1%"
			(at 0 0 0)
			(unlocked yes)
			(layer "F.Fab")
			(hide yes)
			(effects
				(font
					(size 1 1)
					(thickness 0.15)
				)
			)
		)
		(sheetname "/NVMe & microSD/")
		(sheetfile "nvme-micro-sd.kicad_sch")
		(attr smd)
		(fp_rect
			(start -0.925 -0.47)
			(end 0.925 0.47)
			(stroke
				(width 0.05)
				(type default)
			)
			(fill no)
			(layer "F.CrtYd")
		)
		(fp_rect
			(start -0.5 -0.25)
			(end 0.5 0.25)
			(stroke
				(width 0.15)
				(type solid)
			)
			(fill no)
			(layer "F.Fab")
		)
		(fp_text user "${REFERENCE}"
			(at -0.95 3.168 0)
			(layer "F.Fab")
			(effects
				(font
					(size 0.7 0.7)
					(thickness 0.15)
				)
				(justify left bottom)
			)
		)
		(fp_text user "Author: Antmicro"
			(at -0.95 4.169 0)
			(layer "F.Fab")
			(effects
				(font
					(size 0.7 0.7)
					(thickness 0.15)
				)
				(justify left bottom)
			)
		)
		(fp_text user "License: Apache-2.0"
			(at -0.95 5.169 0)
			(layer "F.Fab")
			(effects
				(font
					(size 0.7 0.7)
					(thickness 0.15)
				)
				(justify left bottom)
			)
		)
		(pad "1" smd roundrect
			(at -0.48 0)
			(size 0.59 0.64)
			(layers "F.Cu" "F.Mask" "F.Paste")
			(roundrect_rratio 0.25)
			(net 9 "+3V3")
			(pintype "passive")
		)
		(pad "2" smd roundrect
			(at 0.48 0)
			(size 0.59 0.64)
			(layers "F.Cu" "F.Mask" "F.Paste")
			(roundrect_rratio 0.25)
			(net 7 "/Compute module/SDIO.CLK")
			(pintype "passive")
		)
	)
)
